FILE_TYPE = CONNECTIVITY;
{Allegro Design Entry HDL 17.2-2016 S081 (4005846) 1/11/2022}
"PAGE_NUMBER" = 97;
0"NC";
1"P12V_S3_AUX_CPU0_NVDIMM\g";
2"P3V3_AUX\g";
3"P3V3_AUX\g";
4"P12V_S3_AUX_CPU0_NVDIMM\g";
5"GND\g";
6"GND\g";
7"GND\g";
8"GND\g";
9"GND\g";
10"M_H_CPU0_SB_DQ<31:0>";
11"M_H_CPU0_SA_DQ<31:0>";
12"M_H_CPU0_SB_CB<7:0>";
13"M_H_CPU0_SA_CB<7:0>";
14"M_H_CPU0_SB_CA<6:0>";
15"M_H_CPU0_SA_CA<6:0>";
16"M_H_CPU0_SB_DQS_DP<9:0>";
17"M_H_CPU0_SA_DQS_DP<9:0>";
18"M_H_CPU0_SB_DQS_DN<9:0>";
19"M_H_CPU0_SA_DQS_DN<9:0>";
20"M_H_CPU0_ALERT_N";
21"PD_CHH_CPU0_DIMM2_SAA";
22"I3C_SPD_DDREFGH_CPU0_LVC1_SDA";
23"RST_M_GH_CPU0_FPGA_N";
24"I3C_SPD_DDREFGH_CPU0_LVC1_SCL_R8";
25"I3C_SPD_DDREFGH_CPU0_LVC1_SCL";
26"PWRGD_CHH_CPU0_DIMM2";
27"M_H_CPU0_SB_CB<0>";
28"M_H_CPU0_SB_CB<1>";
29"M_H_CPU0_SB_CB<2>";
30"TP_CHH_CPU0_DIMM2_FRU_6";
31"M_H_CPU0_SB_CB<3>";
32"M_H_CPU0_SB_CB<4>";
33"M_H_CPU0_SB_CB<5>";
34"M_H_CPU0_SB_CB<7>";
35"M_H_CPU0_SA_CB<0>";
36"M_H_CPU0_SA_CB<1>";
37"M_H_CPU0_CLK_DN<1>";
38"M_H_CPU0_CLK_DP<1>";
39"M_H_CPU0_SB_DQS_DN<2>";
40"M_H_CPU0_SA_DQS_DN<9>";
41"M_H_CPU0_SA_DQS_DN<8>";
42"M_H_CPU0_SA_DQS_DN<7>";
43"M_H_CPU0_SA_DQS_DN<5>";
44"M_H_CPU0_SA_DQS_DN<6>";
45"M_H_CPU0_SA_DQS_DN<4>";
46"M_H_CPU0_SA_DQS_DN<3>";
47"M_H_CPU0_SA_DQS_DN<2>";
48"M_H_CPU0_SA_DQS_DN<0>";
49"M_H_CPU0_SA_DQS_DN<1>";
50"M_H_CPU0_SB_DQS_DN<9>";
51"M_H_CPU0_SB_DQS_DN<8>";
52"M_H_CPU0_SB_DQS_DN<7>";
53"M_H_CPU0_SB_DQS_DN<6>";
54"M_H_CPU0_SB_DQS_DN<4>";
55"M_H_CPU0_SB_DQS_DN<5>";
56"M_H_CPU0_SB_DQS_DN<3>";
57"M_H_CPU0_SB_DQS_DN<0>";
58"M_H_CPU0_SB_DQS_DN<1>";
59"M_H_CPU0_SA_DQS_DP<9>";
60"M_H_CPU0_SA_DQS_DP<8>";
61"M_H_CPU0_SA_DQS_DP<7>";
62"M_H_CPU0_SA_DQS_DP<6>";
63"M_H_CPU0_SA_DQS_DP<5>";
64"M_H_CPU0_SA_DQS_DP<4>";
65"M_H_CPU0_SA_DQS_DP<3>";
66"M_H_CPU0_SA_DQS_DP<2>";
67"M_H_CPU0_SA_DQS_DP<1>";
68"M_H_CPU0_SA_DQS_DP<0>";
69"M_H_CPU0_SB_DQS_DP<9>";
70"M_H_CPU0_SB_DQS_DP<8>";
71"M_H_CPU0_SB_DQS_DP<7>";
72"M_H_CPU0_SB_DQS_DP<6>";
73"M_H_CPU0_SB_DQS_DP<5>";
74"M_H_CPU0_SB_DQS_DP<4>";
75"M_H_CPU0_SB_DQS_DP<3>";
76"M_H_CPU0_SB_DQS_DP<2>";
77"M_H_CPU0_SB_DQS_DP<1>";
78"M_H_CPU0_SB_DQS_DP<0>";
79"TP_CHH_CPU0_DIMM2_FRU_0";
80"M_H_CPU0_SA_RSP<1>";
81"M_H_CPU0_SB_RSP<1>";
82"M_H_CPU0_SB_CS_N<2>";
83"M_H_CPU0_SB_CS_N<3>";
84"M_H_CPU0_SA_CS_N<3>";
85"M_H_CPU0_SB_PAR";
86"M_H_CPU0_SA_PAR";
87"M_H_CPU0_SA_CS_N<2>";
88"M_H_CPU0_SA_DQ<25>";
89"M_H_CPU0_SA_DQ<20>";
90"M_H_CPU0_SA_DQ<19>";
91"M_H_CPU0_SA_DQ<18>";
92"M_H_CPU0_SA_DQ<21>";
93"M_H_CPU0_SA_DQ<15>";
94"M_H_CPU0_SA_DQ<14>";
95"M_H_CPU0_SA_DQ<13>";
96"M_H_CPU0_SA_DQ<1>";
97"M_H_CPU0_SA_DQ<2>";
98"M_H_CPU0_SA_DQ<31>";
99"M_H_CPU0_SA_CB<7>";
100"M_H_CPU0_SA_CB<4>";
101"M_H_CPU0_SA_CA<0>";
102"M_H_CPU0_SB_CA<0>";
103"M_H_CPU0_SA_CA<1>";
104"M_H_CPU0_SB_CA<1>";
105"M_H_CPU0_SA_CA<2>";
106"M_H_CPU0_SB_CA<2>";
107"M_H_CPU0_SA_CA<3>";
108"M_H_CPU0_SB_CA<3>";
109"M_H_CPU0_SA_CA<4>";
110"M_H_CPU0_SB_CA<4>";
111"M_H_CPU0_SA_CA<5>";
112"M_H_CPU0_SB_CA<5>";
113"M_H_CPU0_SA_CA<6>";
114"M_H_CPU0_SB_CA<6>";
115"M_H_CPU0_SA_CB<6>";
116"M_H_CPU0_SA_CB<5>";
117"M_H_CPU0_SA_CB<3>";
118"M_H_CPU0_SA_CB<2>";
119"M_H_CPU0_SB_CB<6>";
120"M_H_CPU0_SA_DQ<30>";
121"M_H_CPU0_SA_DQ<29>";
122"M_H_CPU0_SA_DQ<28>";
123"M_H_CPU0_SA_DQ<27>";
124"M_H_CPU0_SA_DQ<26>";
125"M_H_CPU0_SA_DQ<24>";
126"M_H_CPU0_SA_DQ<23>";
127"M_H_CPU0_SA_DQ<22>";
128"M_H_CPU0_SA_DQ<17>";
129"M_H_CPU0_SA_DQ<16>";
130"M_H_CPU0_SA_DQ<12>";
131"M_H_CPU0_SA_DQ<11>";
132"M_H_CPU0_SA_DQ<10>";
133"M_H_CPU0_SA_DQ<9>";
134"M_H_CPU0_SA_DQ<8>";
135"M_H_CPU0_SA_DQ<7>";
136"M_H_CPU0_SA_DQ<6>";
137"M_H_CPU0_SA_DQ<5>";
138"M_H_CPU0_SA_DQ<4>";
139"M_H_CPU0_SA_DQ<3>";
140"M_H_CPU0_SA_DQ<0>";
141"M_H_CPU0_SB_DQ<31>";
142"M_H_CPU0_SB_DQ<30>";
143"M_H_CPU0_SB_DQ<29>";
144"M_H_CPU0_SB_DQ<28>";
145"M_H_CPU0_SB_DQ<27>";
146"M_H_CPU0_SB_DQ<26>";
147"M_H_CPU0_SB_DQ<25>";
148"M_H_CPU0_SB_DQ<24>";
149"M_H_CPU0_SB_DQ<23>";
150"M_H_CPU0_SB_DQ<22>";
151"M_H_CPU0_SB_DQ<21>";
152"M_H_CPU0_SB_DQ<20>";
153"M_H_CPU0_SB_DQ<19>";
154"M_H_CPU0_SB_DQ<18>";
155"M_H_CPU0_SB_DQ<17>";
156"M_H_CPU0_SB_DQ<16>";
157"M_H_CPU0_SB_DQ<15>";
158"M_H_CPU0_SB_DQ<14>";
159"M_H_CPU0_SB_DQ<13>";
160"M_H_CPU0_SB_DQ<12>";
161"M_H_CPU0_SB_DQ<11>";
162"M_H_CPU0_SB_DQ<10>";
163"M_H_CPU0_SB_DQ<9>";
164"M_H_CPU0_SB_DQ<8>";
165"M_H_CPU0_SB_DQ<7>";
166"M_H_CPU0_SB_DQ<6>";
167"M_H_CPU0_SB_DQ<5>";
168"M_H_CPU0_SB_DQ<4>";
169"M_H_CPU0_SB_DQ<3>";
170"M_H_CPU0_SB_DQ<2>";
171"M_H_CPU0_SB_DQ<1>";
172"M_H_CPU0_SB_DQ<0>";
173"TP_CHH_CPU0_DIMM2_FRU_5";
174"TP_CHH_CPU0_DIMM2_FRU_4";
175"TP_CHH_CPU0_DIMM2_FRU_3";
176"TP_CHH_CPU0_DIMM2_FRU_2";
177"TP_CHH_CPU0_DIMM2_FRU_1";
178"PD_CHH_CPU0_DIMM2_SAA";
%"TAP"
"1","(-350,2675)","0","standard","I100";
;
CDS_LIB"standard"
BODY_TYPE"PLUMBING"
HDL_TAP"TRUE";
"B \NAC \NWC"11;
"S \NAC"
BN"1"96;
%"TAP"
"1","(-350,2775)","0","standard","I101";
;
CDS_LIB"standard"
BODY_TYPE"PLUMBING"
HDL_TAP"TRUE";
"B \NAC \NWC"11;
"S \NAC"
BN"3"139;
%"TAP"
"1","(-350,2825)","0","standard","I102";
;
CDS_LIB"standard"
BODY_TYPE"PLUMBING"
HDL_TAP"TRUE";
"B \NAC \NWC"11;
"S \NAC"
BN"4"138;
%"TAP"
"1","(-350,2875)","0","standard","I103";
;
CDS_LIB"standard"
BODY_TYPE"PLUMBING"
HDL_TAP"TRUE";
"B \NAC \NWC"11;
"S \NAC"
BN"5"137;
%"TAP"
"1","(-350,2975)","0","standard","I105";
;
CDS_LIB"standard"
BODY_TYPE"PLUMBING"
HDL_TAP"TRUE";
"B \NAC \NWC"11;
"S \NAC"
BN"7"135;
%"TAP"
"1","(-350,2925)","0","standard","I106";
;
CDS_LIB"standard"
BODY_TYPE"PLUMBING"
HDL_TAP"TRUE";
"B \NAC \NWC"11;
"S \NAC"
BN"6"136;
%"TAP"
"1","(-350,3025)","0","standard","I107";
;
CDS_LIB"standard"
BODY_TYPE"PLUMBING"
HDL_TAP"TRUE";
"B \NAC \NWC"11;
"S \NAC"
BN"8"134;
%"TAP"
"1","(-350,3125)","0","standard","I108";
;
CDS_LIB"standard"
BODY_TYPE"PLUMBING"
HDL_TAP"TRUE";
"B \NAC \NWC"11;
"S \NAC"
BN"10"132;
%"TAP"
"1","(-350,3075)","0","standard","I109";
;
CDS_LIB"standard"
BODY_TYPE"PLUMBING"
HDL_TAP"TRUE";
"B \NAC \NWC"11;
"S \NAC"
BN"9"133;
%"TAP"
"1","(-350,3225)","0","standard","I110";
;
CDS_LIB"standard"
BODY_TYPE"PLUMBING"
HDL_TAP"TRUE";
"B \NAC \NWC"11;
"S \NAC"
BN"12"130;
%"TAP"
"1","(-350,3175)","0","standard","I111";
;
CDS_LIB"standard"
BODY_TYPE"PLUMBING"
HDL_TAP"TRUE";
"B \NAC \NWC"11;
"S \NAC"
BN"11"131;
%"TAP"
"1","(-350,3275)","0","standard","I112";
;
CDS_LIB"standard"
BODY_TYPE"PLUMBING"
HDL_TAP"TRUE";
"B \NAC \NWC"11;
"S \NAC"
BN"13"95;
%"TAP"
"1","(-350,3375)","0","standard","I113";
;
CDS_LIB"standard"
BODY_TYPE"PLUMBING"
HDL_TAP"TRUE";
"B \NAC \NWC"11;
"S \NAC"
BN"15"93;
%"TAP"
"1","(-350,3325)","0","standard","I114";
;
CDS_LIB"standard"
BODY_TYPE"PLUMBING"
HDL_TAP"TRUE";
"B \NAC \NWC"11;
"S \NAC"
BN"14"94;
%"TAP"
"1","(-350,3425)","0","standard","I115";
;
CDS_LIB"standard"
BODY_TYPE"PLUMBING"
HDL_TAP"TRUE";
"B \NAC \NWC"11;
"S \NAC"
BN"16"129;
%"TAP"
"1","(-350,3525)","0","standard","I116";
;
CDS_LIB"standard"
BODY_TYPE"PLUMBING"
HDL_TAP"TRUE";
"B \NAC \NWC"11;
"S \NAC"
BN"18"91;
%"TAP"
"1","(-350,3475)","0","standard","I117";
;
CDS_LIB"standard"
BODY_TYPE"PLUMBING"
HDL_TAP"TRUE";
"B \NAC \NWC"11;
"S \NAC"
BN"17"128;
%"TAP"
"1","(-350,3625)","0","standard","I118";
;
CDS_LIB"standard"
BODY_TYPE"PLUMBING"
HDL_TAP"TRUE";
"B \NAC \NWC"11;
"S \NAC"
BN"20"89;
%"TAP"
"1","(-350,3575)","0","standard","I119";
;
CDS_LIB"standard"
BODY_TYPE"PLUMBING"
HDL_TAP"TRUE";
"B \NAC \NWC"11;
"S \NAC"
BN"19"90;
%"TAP"
"1","(-350,3725)","0","standard","I120";
;
CDS_LIB"standard"
BODY_TYPE"PLUMBING"
HDL_TAP"TRUE";
"B \NAC \NWC"11;
"S \NAC"
BN"22"127;
%"TAP"
"1","(-350,3675)","0","standard","I121";
;
CDS_LIB"standard"
BODY_TYPE"PLUMBING"
HDL_TAP"TRUE";
"B \NAC \NWC"11;
"S \NAC"
BN"21"92;
%"TAP"
"1","(-350,3775)","0","standard","I122";
;
CDS_LIB"standard"
BODY_TYPE"PLUMBING"
HDL_TAP"TRUE";
"B \NAC \NWC"11;
"S \NAC"
BN"23"126;
%"TAP"
"1","(-350,3875)","0","standard","I123";
;
CDS_LIB"standard"
BODY_TYPE"PLUMBING"
HDL_TAP"TRUE";
"B \NAC \NWC"11;
"S \NAC"
BN"25"88;
%"TAP"
"1","(-350,3825)","0","standard","I124";
;
CDS_LIB"standard"
BODY_TYPE"PLUMBING"
HDL_TAP"TRUE";
"B \NAC \NWC"11;
"S \NAC"
BN"24"125;
%"TAP"
"1","(-350,3925)","0","standard","I125";
;
CDS_LIB"standard"
BODY_TYPE"PLUMBING"
HDL_TAP"TRUE";
"B \NAC \NWC"11;
"S \NAC"
BN"26"124;
%"TAP"
"1","(-350,4025)","0","standard","I126";
;
CDS_LIB"standard"
BODY_TYPE"PLUMBING"
HDL_TAP"TRUE";
"B \NAC \NWC"11;
"S \NAC"
BN"28"122;
%"TAP"
"1","(-350,3975)","0","standard","I127";
;
CDS_LIB"standard"
BODY_TYPE"PLUMBING"
HDL_TAP"TRUE";
"B \NAC \NWC"11;
"S \NAC"
BN"27"123;
%"TAP"
"1","(-350,4175)","0","standard","I128";
;
CDS_LIB"standard"
BODY_TYPE"PLUMBING"
HDL_TAP"TRUE";
"B \NAC \NWC"11;
"S \NAC"
BN"31"98;
%"TAP"
"1","(-350,4075)","0","standard","I129";
;
CDS_LIB"standard"
BODY_TYPE"PLUMBING"
HDL_TAP"TRUE";
"B \NAC \NWC"11;
"S \NAC"
BN"29"121;
%"TAP"
"1","(-350,4125)","0","standard","I130";
;
CDS_LIB"standard"
BODY_TYPE"PLUMBING"
HDL_TAP"TRUE";
"B \NAC \NWC"11;
"S \NAC"
BN"30"120;
%"TAP"
"1","(2400,2225)","0","standard","I133";
;
CDS_LIB"standard"
BODY_TYPE"PLUMBING"
HDL_TAP"TRUE";
"B \NAC \NWC"16;
"S \NAC"
BN"0"78;
%"TAP"
"1","(2400,2325)","0","standard","I134";
;
CDS_LIB"standard"
BODY_TYPE"PLUMBING"
HDL_TAP"TRUE";
"B \NAC \NWC"16;
"S \NAC"
BN"1"77;
%"TAP"
"1","(2575,2275)","0","standard","I135";
;
CDS_LIB"standard"
BODY_TYPE"PLUMBING"
HDL_TAP"TRUE";
"B \NAC \NWC"18;
"S \NAC"
BN"1"58;
%"TAP"
"1","(2575,2175)","0","standard","I136";
;
CDS_LIB"standard"
BODY_TYPE"PLUMBING"
HDL_TAP"TRUE";
"B \NAC \NWC"18;
"S \NAC"
BN"0"57;
%"TAP"
"1","(2575,2375)","0","standard","I137";
;
CDS_LIB"standard"
BODY_TYPE"PLUMBING"
HDL_TAP"TRUE";
"B \NAC \NWC"18;
"S \NAC"
BN"2"39;
%"TAP"
"1","(2400,2425)","0","standard","I138";
;
CDS_LIB"standard"
BODY_TYPE"PLUMBING"
HDL_TAP"TRUE";
"B \NAC \NWC"16;
"S \NAC"
BN"2"76;
%"TAP"
"1","(2400,2625)","0","standard","I139";
;
CDS_LIB"standard"
BODY_TYPE"PLUMBING"
HDL_TAP"TRUE";
"B \NAC \NWC"16;
"S \NAC"
BN"4"74;
%"TAP"
"1","(2400,2525)","0","standard","I140";
;
CDS_LIB"standard"
BODY_TYPE"PLUMBING"
HDL_TAP"TRUE";
"B \NAC \NWC"16;
"S \NAC"
BN"3"75;
%"TAP"
"1","(2400,2825)","0","standard","I141";
;
CDS_LIB"standard"
BODY_TYPE"PLUMBING"
HDL_TAP"TRUE";
"B \NAC \NWC"16;
"S \NAC"
BN"6"72;
%"TAP"
"1","(2400,2725)","0","standard","I142";
;
CDS_LIB"standard"
BODY_TYPE"PLUMBING"
HDL_TAP"TRUE";
"B \NAC \NWC"16;
"S \NAC"
BN"5"73;
%"TAP"
"1","(2575,2575)","0","standard","I143";
;
CDS_LIB"standard"
BODY_TYPE"PLUMBING"
HDL_TAP"TRUE";
"B \NAC \NWC"18;
"S \NAC"
BN"4"54;
%"TAP"
"1","(2575,2475)","0","standard","I144";
;
CDS_LIB"standard"
BODY_TYPE"PLUMBING"
HDL_TAP"TRUE";
"B \NAC \NWC"18;
"S \NAC"
BN"3"56;
%"TAP"
"1","(2575,2675)","0","standard","I145";
;
CDS_LIB"standard"
BODY_TYPE"PLUMBING"
HDL_TAP"TRUE";
"B \NAC \NWC"18;
"S \NAC"
BN"5"55;
%"TAP"
"1","(2575,2875)","0","standard","I146";
;
CDS_LIB"standard"
BODY_TYPE"PLUMBING"
HDL_TAP"TRUE";
"B \NAC \NWC"18;
"S \NAC"
BN"7"52;
%"TAP"
"1","(2575,2775)","0","standard","I147";
;
CDS_LIB"standard"
BODY_TYPE"PLUMBING"
HDL_TAP"TRUE";
"B \NAC \NWC"18;
"S \NAC"
BN"6"53;
%"TAP"
"1","(2400,2925)","0","standard","I148";
;
CDS_LIB"standard"
BODY_TYPE"PLUMBING"
HDL_TAP"TRUE";
"B \NAC \NWC"16;
"S \NAC"
BN"7"71;
%"TAP"
"1","(2400,3025)","0","standard","I149";
;
CDS_LIB"standard"
BODY_TYPE"PLUMBING"
HDL_TAP"TRUE";
"B \NAC \NWC"16;
"S \NAC"
BN"8"70;
%"TAP"
"1","(2400,3125)","0","standard","I150";
;
CDS_LIB"standard"
BODY_TYPE"PLUMBING"
HDL_TAP"TRUE";
"B \NAC \NWC"16;
"S \NAC"
BN"9"69;
%"TAP"
"1","(2400,3375)","0","standard","I151";
;
CDS_LIB"standard"
BODY_TYPE"PLUMBING"
HDL_TAP"TRUE";
"B \NAC \NWC"17;
"S \NAC"
BN"1"67;
%"TAP"
"1","(2400,3275)","0","standard","I152";
;
CDS_LIB"standard"
BODY_TYPE"PLUMBING"
HDL_TAP"TRUE";
"B \NAC \NWC"17;
"S \NAC"
BN"0"68;
%"TAP"
"1","(2575,2975)","0","standard","I153";
;
CDS_LIB"standard"
BODY_TYPE"PLUMBING"
HDL_TAP"TRUE";
"B \NAC \NWC"18;
"S \NAC"
BN"8"51;
%"TAP"
"1","(2575,3075)","0","standard","I154";
;
CDS_LIB"standard"
BODY_TYPE"PLUMBING"
HDL_TAP"TRUE";
"B \NAC \NWC"18;
"S \NAC"
BN"9"50;
%"TAP"
"1","(2575,3325)","0","standard","I155";
;
CDS_LIB"standard"
BODY_TYPE"PLUMBING"
HDL_TAP"TRUE";
"B \NAC \NWC"19;
"S \NAC"
BN"1"49;
%"TAP"
"1","(2575,3225)","0","standard","I156";
;
CDS_LIB"standard"
BODY_TYPE"PLUMBING"
HDL_TAP"TRUE";
"B \NAC \NWC"19;
"S \NAC"
BN"0"48;
%"TAP"
"1","(2400,3475)","0","standard","I157";
;
CDS_LIB"standard"
BODY_TYPE"PLUMBING"
HDL_TAP"TRUE";
"B \NAC \NWC"17;
"S \NAC"
BN"2"66;
%"TAP"
"1","(2400,3575)","0","standard","I158";
;
CDS_LIB"standard"
BODY_TYPE"PLUMBING"
HDL_TAP"TRUE";
"B \NAC \NWC"17;
"S \NAC"
BN"3"65;
%"TAP"
"1","(2400,3775)","0","standard","I159";
;
CDS_LIB"standard"
BODY_TYPE"PLUMBING"
HDL_TAP"TRUE";
"B \NAC \NWC"17;
"S \NAC"
BN"5"63;
%"TAP"
"1","(2400,3675)","0","standard","I160";
;
CDS_LIB"standard"
BODY_TYPE"PLUMBING"
HDL_TAP"TRUE";
"B \NAC \NWC"17;
"S \NAC"
BN"4"64;
%"TAP"
"1","(2400,3875)","0","standard","I161";
;
CDS_LIB"standard"
BODY_TYPE"PLUMBING"
HDL_TAP"TRUE";
"B \NAC \NWC"17;
"S \NAC"
BN"6"62;
%"TAP"
"1","(2575,3425)","0","standard","I162";
;
CDS_LIB"standard"
BODY_TYPE"PLUMBING"
HDL_TAP"TRUE";
"B \NAC \NWC"19;
"S \NAC"
BN"2"47;
%"TAP"
"1","(2575,3525)","0","standard","I163";
;
CDS_LIB"standard"
BODY_TYPE"PLUMBING"
HDL_TAP"TRUE";
"B \NAC \NWC"19;
"S \NAC"
BN"3"46;
%"TAP"
"1","(2575,3625)","0","standard","I164";
;
CDS_LIB"standard"
BODY_TYPE"PLUMBING"
HDL_TAP"TRUE";
"B \NAC \NWC"19;
"S \NAC"
BN"4"45;
%"TAP"
"1","(2575,3725)","0","standard","I165";
;
CDS_LIB"standard"
BODY_TYPE"PLUMBING"
HDL_TAP"TRUE";
"B \NAC \NWC"19;
"S \NAC"
BN"5"43;
%"TAP"
"1","(2575,3825)","0","standard","I166";
;
CDS_LIB"standard"
BODY_TYPE"PLUMBING"
HDL_TAP"TRUE";
"B \NAC \NWC"19;
"S \NAC"
BN"6"44;
%"TAP"
"1","(2400,3975)","0","standard","I167";
;
CDS_LIB"standard"
BODY_TYPE"PLUMBING"
HDL_TAP"TRUE";
"B \NAC \NWC"17;
"S \NAC"
BN"7"61;
%"TAP"
"1","(2400,4175)","0","standard","I168";
;
CDS_LIB"standard"
BODY_TYPE"PLUMBING"
HDL_TAP"TRUE";
"B \NAC \NWC"17;
"S \NAC"
BN"9"59;
%"TAP"
"1","(2400,4075)","0","standard","I169";
;
CDS_LIB"standard"
BODY_TYPE"PLUMBING"
HDL_TAP"TRUE";
"B \NAC \NWC"17;
"S \NAC"
BN"8"60;
%"TAP"
"1","(2575,4025)","0","standard","I170";
;
CDS_LIB"standard"
BODY_TYPE"PLUMBING"
HDL_TAP"TRUE";
"B \NAC \NWC"19;
"S \NAC"
BN"8"41;
%"TAP"
"1","(2575,3925)","0","standard","I171";
;
CDS_LIB"standard"
BODY_TYPE"PLUMBING"
HDL_TAP"TRUE";
"B \NAC \NWC"19;
"S \NAC"
BN"7"42;
%"TAP"
"1","(2575,4125)","0","standard","I172";
;
CDS_LIB"standard"
BODY_TYPE"PLUMBING"
HDL_TAP"TRUE";
"B \NAC \NWC"19;
"S \NAC"
BN"9"40;
%"VCC_CORE"
"1","(4075,4725)","0","logical_power","I177";
;
HDL_POWER"P12V_S3_AUX_CPU0_NVDIMM"
CDS_LIB"logical_power";
"A"4;
%"SCONN288_ADR50017P087CC"
"2","(1475,3175)","0","pure_quanta","I178";
;
PART_NUMBER"DFHST8FS460"
PART_TYPE"SMLF"
MATERIAL"IO"
VALUE"SCONN288_ADR50017-P087CC"
LOCATION"J16"
NEEDS_NO_SIZE"TRUE"
CDS_LMAN_SYM_OUTLINE"-600,1150,600,-1150"
CDS_LIB"pure_quanta"
$SEC"2"
CDS_SEC"2";
"DQS7_A_C||TDQS7_A_C \B"
$PN"178"42;
"DQS6_A_T||TDQS6_A_T"
$PN"168"62;
"DQS8_B_T||TDQS8_B_T"
$PN"283"70;
"DQS8_B_C||TDQS8_B_C \B"
$PN"282"51;
"DQS7_B_T||TDQS7_B_T"
$PN"272"71;
"DQS0_A_C \B"
$PN"12"48;
"DQS0_A_T"
$PN"11"68;
"DQS0_B_C \B"
$PN"105"57;
"DQS0_B_T"
$PN"104"78;
"DQS1_A_C \B"
$PN"23"49;
"DQS1_A_T"
$PN"22"67;
"DQS1_B_C \B"
$PN"116"58;
"DQS1_B_T"
$PN"115"77;
"DQS2_A_C \B"
$PN"34"47;
"DQS2_A_T"
$PN"33"66;
"DQS2_B_C \B"
$PN"127"39;
"DQS2_B_T"
$PN"126"76;
"DQS3_A_C \B"
$PN"45"46;
"DQS3_A_T"
$PN"44"65;
"DQS3_B_C \B"
$PN"138"56;
"DQS3_B_T"
$PN"137"75;
"DQS4_A_C \B"
$PN"56"45;
"DQS4_A_T"
$PN"55"64;
"DQS4_B_C \B"
$PN"238"54;
"DQS4_B_T"
$PN"239"74;
"DQS5_A_C||TDQS5_A_C||DQS5_A_T||TDQS5_A_T \B"
$PN"156"43;
"DQS5_A_T||TDQS5_A_T"
$PN"157"63;
"DQS5_B_C||TDQS5_B_C \B"
$PN"249"55;
"DQS5_B_T||TDQS5_B_T"
$PN"250"73;
"DQS6_A_C||TDQS6_A_C||DQS6_A_T||TDQS6_A_T \B"
$PN"167"44;
"DQS6_B_C||TDQS6_B_C \B"
$PN"260"53;
"DQS6_B_T||TDQS6_B_T"
$PN"261"72;
"DQS7_A_T||TDQS7_A_T"
$PN"179"61;
"DQS7_B_C||TDQS7_B_C \B"
$PN"271"52;
"DQS8_A_C||TDQS8_A_C \B"
$PN"189"41;
"DQS8_A_T||TDQS8_A_T"
$PN"190"60;
"DQS9_A_C||TDQS9_A_C \B"
$PN"200"40;
"DQS9_A_T||TDQS9_A_T"
$PN"201"59;
"DQS9_B_C||TDQS9_B_C \B"
$PN"94"50;
"DQS9_B_T||TDQS9_B_T||DBI4_B_N"
$PN"93"69;
%"Q_RES"
"1","(-2975,1450)","0","pure_quanta","I179";
;
PART_NUMBER"CS04992FB07"
VALUE"49.9"
MATERIAL"CHIP"
$LOCATION"R3890"
CDS_LIB"pure_quanta"
PACK_TYPE"0402LF"
TOLERANCE"1%"
WATTAGE"1/16W"
CDS_LOCATION"R3890"
$SEC"1"
CDS_SEC"1";
"B"
$PN"2"25;
"A"
$PN"1"24;
%"VCC_CORE"
"1","(-2825,2050)","0","logical_power","I25";
;
HDL_POWER"P3V3_AUX"
CDS_LIB"logical_power";
"A"2;
%"TAP"
"1","(-2000,1975)","2","standard","I26";
;
CDS_LIB"standard"
BODY_TYPE"PLUMBING"
HDL_TAP"TRUE";
"B \NAC \NWC"12;
"S \NAC"
BN"0"27;
%"TAP"
"1","(-2000,2075)","2","standard","I27";
;
CDS_LIB"standard"
BODY_TYPE"PLUMBING"
HDL_TAP"TRUE";
"B \NAC \NWC"12;
"S \NAC"
BN"2"29;
%"TAP"
"1","(-2000,2025)","2","standard","I28";
;
CDS_LIB"standard"
BODY_TYPE"PLUMBING"
HDL_TAP"TRUE";
"B \NAC \NWC"12;
"S \NAC"
BN"1"28;
%"TAP"
"1","(-2000,2125)","2","standard","I29";
;
CDS_LIB"standard"
BODY_TYPE"PLUMBING"
HDL_TAP"TRUE";
"B \NAC \NWC"12;
"S \NAC"
BN"3"31;
%"TAP"
"1","(-2000,2225)","2","standard","I30";
;
CDS_LIB"standard"
BODY_TYPE"PLUMBING"
HDL_TAP"TRUE";
"B \NAC \NWC"12;
"S \NAC"
BN"5"33;
%"TAP"
"1","(-2000,2175)","2","standard","I31";
;
CDS_LIB"standard"
BODY_TYPE"PLUMBING"
HDL_TAP"TRUE";
"B \NAC \NWC"12;
"S \NAC"
BN"4"32;
%"TAP"
"1","(-2000,2275)","2","standard","I32";
;
CDS_LIB"standard"
BODY_TYPE"PLUMBING"
HDL_TAP"TRUE";
"B \NAC \NWC"12;
"S \NAC"
BN"6"119;
%"TAP"
"1","(-2000,2325)","2","standard","I33";
;
CDS_LIB"standard"
BODY_TYPE"PLUMBING"
HDL_TAP"TRUE";
"B \NAC \NWC"12;
"S \NAC"
BN"7"34;
%"TAP"
"1","(-2000,2425)","2","standard","I34";
;
CDS_LIB"standard"
BODY_TYPE"PLUMBING"
HDL_TAP"TRUE";
"B \NAC \NWC"13;
"S \NAC"
BN"0"35;
%"TAP"
"1","(-2000,2475)","2","standard","I35";
;
CDS_LIB"standard"
BODY_TYPE"PLUMBING"
HDL_TAP"TRUE";
"B \NAC \NWC"13;
"S \NAC"
BN"1"36;
%"TAP"
"1","(-2000,2575)","2","standard","I36";
;
CDS_LIB"standard"
BODY_TYPE"PLUMBING"
HDL_TAP"TRUE";
"B \NAC \NWC"13;
"S \NAC"
BN"3"117;
%"TAP"
"1","(-2000,2525)","2","standard","I37";
;
CDS_LIB"standard"
BODY_TYPE"PLUMBING"
HDL_TAP"TRUE";
"B \NAC \NWC"13;
"S \NAC"
BN"2"118;
%"TAP"
"1","(-2000,2625)","2","standard","I38";
;
CDS_LIB"standard"
BODY_TYPE"PLUMBING"
HDL_TAP"TRUE";
"B \NAC \NWC"13;
"S \NAC"
BN"4"100;
%"TAP"
"1","(-2000,2725)","2","standard","I39";
;
CDS_LIB"standard"
BODY_TYPE"PLUMBING"
HDL_TAP"TRUE";
"B \NAC \NWC"13;
"S \NAC"
BN"6"115;
%"UNIVERSAL_GND"
"1","(-1775,-200)","0","logical_power","I4";
;
CDS_LIB"logical_power"
HDL_POWER"GND";
"A"9;
%"TAP"
"1","(-2000,2675)","2","standard","I40";
;
CDS_LIB"standard"
BODY_TYPE"PLUMBING"
HDL_TAP"TRUE";
"B \NAC \NWC"13;
"S \NAC"
BN"5"116;
%"TAP"
"1","(-2000,2775)","2","standard","I41";
;
CDS_LIB"standard"
BODY_TYPE"PLUMBING"
HDL_TAP"TRUE";
"B \NAC \NWC"13;
"S \NAC"
BN"7"99;
%"TAP"
"1","(-2000,3525)","2","standard","I42";
;
CDS_LIB"standard"
BODY_TYPE"PLUMBING"
HDL_TAP"TRUE";
"B \NAC \NWC"14;
"S \NAC"
BN"1"104;
%"TAP"
"1","(-2000,3475)","2","standard","I43";
;
CDS_LIB"standard"
BODY_TYPE"PLUMBING"
HDL_TAP"TRUE";
"B \NAC \NWC"14;
"S \NAC"
BN"0"102;
%"TAP"
"1","(-2000,3625)","2","standard","I44";
;
CDS_LIB"standard"
BODY_TYPE"PLUMBING"
HDL_TAP"TRUE";
"B \NAC \NWC"14;
"S \NAC"
BN"3"108;
%"TAP"
"1","(-2000,3575)","2","standard","I45";
;
CDS_LIB"standard"
BODY_TYPE"PLUMBING"
HDL_TAP"TRUE";
"B \NAC \NWC"14;
"S \NAC"
BN"2"106;
%"TAP"
"1","(-2000,3725)","2","standard","I46";
;
CDS_LIB"standard"
BODY_TYPE"PLUMBING"
HDL_TAP"TRUE";
"B \NAC \NWC"14;
"S \NAC"
BN"5"112;
%"TAP"
"1","(-2000,3675)","2","standard","I47";
;
CDS_LIB"standard"
BODY_TYPE"PLUMBING"
HDL_TAP"TRUE";
"B \NAC \NWC"14;
"S \NAC"
BN"4"110;
%"TAP"
"1","(-2000,3775)","2","standard","I48";
;
CDS_LIB"standard"
BODY_TYPE"PLUMBING"
HDL_TAP"TRUE";
"B \NAC \NWC"14;
"S \NAC"
BN"6"114;
%"TAP"
"1","(-2000,3875)","2","standard","I49";
;
CDS_LIB"standard"
BODY_TYPE"PLUMBING"
HDL_TAP"TRUE";
"B \NAC \NWC"15;
"S \NAC"
BN"0"101;
%"Q_RES"
"2","(-1775,25)","0","pure_quanta","I5";
;
PART_NUMBER"CS41962FB03"
VALUE"196K"
MATERIAL"CHIP"
PACK_TYPE"0402LF"
WATTAGE"1/16W"
TOLERANCE"1%"
$LOCATION"R41"
CDS_LIB"pure_quanta"
CDS_LOCATION"R41"
$SEC"1"
CDS_SEC"1";
"A"
$PN"1"178;
"B"
$PN"2"9;
%"TAP"
"1","(-2000,3925)","2","standard","I50";
;
CDS_LIB"standard"
BODY_TYPE"PLUMBING"
HDL_TAP"TRUE";
"B \NAC \NWC"15;
"S \NAC"
BN"1"103;
%"TAP"
"1","(-2000,3975)","2","standard","I51";
;
CDS_LIB"standard"
BODY_TYPE"PLUMBING"
HDL_TAP"TRUE";
"B \NAC \NWC"15;
"S \NAC"
BN"2"105;
%"TAP"
"1","(-2000,4025)","2","standard","I52";
;
CDS_LIB"standard"
BODY_TYPE"PLUMBING"
HDL_TAP"TRUE";
"B \NAC \NWC"15;
"S \NAC"
BN"3"107;
%"TAP"
"1","(-2000,4125)","2","standard","I53";
;
CDS_LIB"standard"
BODY_TYPE"PLUMBING"
HDL_TAP"TRUE";
"B \NAC \NWC"15;
"S \NAC"
BN"5"111;
%"TAP"
"1","(-2000,4075)","2","standard","I54";
;
CDS_LIB"standard"
BODY_TYPE"PLUMBING"
HDL_TAP"TRUE";
"B \NAC \NWC"15;
"S \NAC"
BN"4"109;
%"TAP"
"1","(-2000,4175)","2","standard","I55";
;
CDS_LIB"standard"
BODY_TYPE"PLUMBING"
HDL_TAP"TRUE";
"B \NAC \NWC"15;
"S \NAC"
BN"6"113;
%"Q_CAP"
"1","(1375,300)","0","pure_quanta","I56";
;
PART_NUMBER"CH5221MEB00"
MATERIAL"X6S"
PACK_TYPE"C0402"
TOLERANCE"20%"
VOLTAGE"6.3V"
VALUE"2.2UF"
$LOCATION"C47"
CDS_LIB"pure_quanta"
CDS_LOCATION"C47"
$SEC"1"
CDS_SEC"1";
"B"
$PN"2"8;
"A"
$PN"1"3;
%"UNIVERSAL_GND"
"1","(1375,-75)","0","logical_power","I57";
;
CDS_LIB"logical_power"
HDL_POWER"GND";
"A"8;
%"VCC_CORE"
"1","(1375,625)","0","logical_power","I58";
;
HDL_POWER"P3V3_AUX"
CDS_LIB"logical_power";
"A"3;
%"Q_CAP"
"1","(2375,300)","0","pure_quanta","I59";
;
PART_NUMBER"CH6103KEA00"
TOLERANCE"10%"
VOLTAGE"16V"
PACK_TYPE"C0805"
MATERIAL"X6S"
VALUE"10UF"
$LOCATION"C48"
CDS_LIB"pure_quanta"
CDS_LOCATION"C48"
$SEC"1"
CDS_SEC"1";
"B"
$PN"2"7;
"A"
$PN"1"1;
%"SCONN288_ADR50017P087CC"
"1","(-1175,2425)","0","pure_quanta","I6";
;
PART_NUMBER"DFHST8FS460"
MATERIAL"IO"
PART_TYPE"SMLF"
VALUE"SCONN288_ADR50017-P087CC"
$LOCATION"J16"
CDS_LIB"pure_quanta"
CDS_LMAN_SYM_OUTLINE"-450,1875,450,-1875"
NEEDS_NO_SIZE"TRUE"
CDS_LOCATION"J16"
$SEC"1"
CDS_SEC"1";
"DQ31_A"
$PN"194"98;
"CB7_A"
$PN"205"99;
"CB4_A"
$PN"58"100;
"CB1_A"
$PN"53"36;
"CB7_B"
$PN"236"34;
"ALERT_N \B"
$PN"62"20;
"CA0_A"
$PN"66"101;
"CA0_B"
$PN"76"102;
"CA1_A"
$PN"211"103;
"CA1_B"
$PN"221"104;
"CA2_A"
$PN"68"105;
"CA2_B"
$PN"78"106;
"CA3_A"
$PN"213"107;
"CA3_B"
$PN"223"108;
"CA4_A"
$PN"70"109;
"CA4_B"
$PN"80"110;
"CA5_A"
$PN"215"111;
"CA5_B"
$PN"225"112;
"CA6_A"
$PN"72"113;
"CA6_B"
$PN"82"114;
"CB6_A"
$PN"203"115;
"CB5_A"
$PN"60"116;
"CB3_A"
$PN"198"117;
"CB2_A"
$PN"196"118;
"CB0_A"
$PN"51"35;
"CB6_B"
$PN"234"119;
"CB5_B"
$PN"91"33;
"CB4_B"
$PN"89"32;
"CB3_B"
$PN"243"31;
"CB2_B"
$PN"241"29;
"CB1_B"
$PN"98"28;
"CB0_B"
$PN"96"27;
"CK_C \B"
$PN"218"37;
"CK_T"
$PN"217"38;
"CS0_A_N"
$PN"64"87;
"CS0_B_N"
$PN"84"82;
"CS1_A_N"
$PN"209"84;
"CS1_B_N"
$PN"229"83;
"DQ30_A"
$PN"192"120;
"DQ29_A"
$PN"49"121;
"DQ28_A"
$PN"47"122;
"DQ27_A"
$PN"187"123;
"DQ26_A"
$PN"185"124;
"DQ25_A"
$PN"42"88;
"DQ24_A"
$PN"40"125;
"DQ23_A"
$PN"183"126;
"DQ22_A"
$PN"181"127;
"DQ21_A"
$PN"38"92;
"DQ20_A"
$PN"36"89;
"DQ19_A"
$PN"176"90;
"DQ18_A"
$PN"174"91;
"DQ17_A"
$PN"31"128;
"DQ16_A"
$PN"29"129;
"DQ15_A"
$PN"172"93;
"DQ14_A"
$PN"170"94;
"DQ13_A"
$PN"27"95;
"DQ12_A"
$PN"25"130;
"DQ11_A"
$PN"165"131;
"DQ10_A"
$PN"163"132;
"DQ9_A"
$PN"20"133;
"DQ8_A"
$PN"18"134;
"DQ7_A"
$PN"161"135;
"DQ6_A"
$PN"159"136;
"DQ5_A"
$PN"16"137;
"DQ4_A"
$PN"14"138;
"DQ3_A"
$PN"154"139;
"DQ2_A"
$PN"152"97;
"DQ1_A"
$PN"9"96;
"DQ0_A"
$PN"7"140;
"DQ31_B"
$PN"287"141;
"DQ30_B"
$PN"285"142;
"DQ29_B"
$PN"142"143;
"DQ28_B"
$PN"140"144;
"DQ27_B"
$PN"280"145;
"DQ26_B"
$PN"278"146;
"DQ25_B"
$PN"135"147;
"DQ24_B"
$PN"133"148;
"DQ23_B"
$PN"276"149;
"DQ22_B"
$PN"274"150;
"DQ21_B"
$PN"131"151;
"DQ20_B"
$PN"129"152;
"DQ19_B"
$PN"269"153;
"DQ18_B"
$PN"267"154;
"DQ17_B"
$PN"124"155;
"DQ16_B"
$PN"122"156;
"DQ15_B"
$PN"265"157;
"DQ14_B"
$PN"263"158;
"DQ13_B"
$PN"120"159;
"DQ12_B"
$PN"118"160;
"DQ11_B"
$PN"258"161;
"DQ10_B"
$PN"256"162;
"DQ9_B"
$PN"113"163;
"DQ8_B"
$PN"111"164;
"DQ7_B"
$PN"254"165;
"DQ6_B"
$PN"252"166;
"DQ5_B"
$PN"109"167;
"DQ4_B"
$PN"107"168;
"DQ3_B"
$PN"247"169;
"DQ2_B"
$PN"245"170;
"DQ1_B"
$PN"102"171;
"DQ0_B"
$PN"100"172;
"HSA"
$PN"148"21;
"HSCL"
$PN"4"24;
"HSDA"
$PN"5"22;
"LBD||RSP_A_N"
$PN"86"80;
"LBS||RSP_B_N"
$PN"87"81;
"PAR_A"
$PN"74"86;
"PAR_B"
$PN"227"85;
"PWR_GOOD||FAIL_N"
$PN"147"26;
"RESET_N \B"
$PN"207"23;
"RFU6"
$PN"232"30;
"RFU5"
$PN"231"173;
"RFU4"
$PN"220"174;
"RFU3"
$PN"150"175;
"RFU2"
$PN"149"176;
"RFU1"
$PN"144"177;
"RFU0"
$PN"2"79;
"VIN_MGMT"
$PN"3"2;
%"VCC_CORE"
"1","(2375,625)","0","logical_power","I60";
;
HDL_POWER"P12V_S3_AUX_CPU0_NVDIMM"
CDS_LIB"logical_power";
"A"1;
%"UNIVERSAL_GND"
"1","(3000,-75)","0","logical_power","I61";
;
CDS_LIB"logical_power"
HDL_POWER"GND";
"A"7;
%"Q_CAP"
"1","(3000,300)","0","pure_quanta","I62";
;
PART_NUMBER"CH6103KEA00"
PACK_TYPE"C0805"
VALUE"10UF"
VOLTAGE"16V"
TOLERANCE"10%"
MATERIAL"X6S"
$LOCATION"C49"
CDS_LIB"pure_quanta"
CDS_LOCATION"C49"
$SEC"1"
CDS_SEC"1";
"B"
$PN"2"7;
"A"
$PN"1"1;
%"UNIVERSAL_GND"
"1","(4075,475)","0","logical_power","I63";
;
CDS_LIB"logical_power"
HDL_POWER"GND";
"A"6;
%"SCONN288_ADR50017P087CC"
"3","(4925,2550)","0","pure_quanta","I64";
;
PART_NUMBER"DFHST8FS460"
MATERIAL"IO"
VALUE"SCONN288_ADR50017-P087CC"
PART_TYPE"SMLF"
$LOCATION"J16"
NEEDS_NO_SIZE"TRUE"
CDS_LMAN_SYM_OUTLINE"-450,1775,450,-1775"
CDS_LIB"pure_quanta"
CDS_LOCATION"J16"
$SEC"3"
CDS_SEC"3";
"G3"
$PN"G3"5;
"G2"
$PN"G2"5;
"G1"
$PN"G1"5;
"VSS62"
$PN"141"5;
"VSS61"
$PN"139"5;
"VSS60"
$PN"136"5;
"VSS58"
$PN"132"5;
"VSS104"
$PN"240"6;
"VSS102"
$PN"235"6;
"VSS100"
$PN"230"6;
"VIN_BULK2"
$PN"146"4;
"VIN_BULK1"
$PN"145"4;
"VIN_BULK0"
$PN"1"4;
"VSS126"
$PN"288"6;
"VSS125"
$PN"286"6;
"VSS124"
$PN"284"6;
"VSS123"
$PN"281"6;
"VSS122"
$PN"279"6;
"VSS121"
$PN"277"6;
"VSS120"
$PN"275"6;
"VSS119"
$PN"273"6;
"VSS118"
$PN"270"6;
"VSS117"
$PN"268"6;
"VSS116"
$PN"266"6;
"VSS115"
$PN"264"6;
"VSS114"
$PN"262"6;
"VSS113"
$PN"259"6;
"VSS112"
$PN"257"6;
"VSS111"
$PN"255"6;
"VSS110"
$PN"253"6;
"VSS109"
$PN"251"6;
"VSS108"
$PN"248"6;
"VSS107"
$PN"246"6;
"VSS106"
$PN"244"6;
"VSS105"
$PN"242"6;
"VSS103"
$PN"237"6;
"VSS101"
$PN"233"6;
"VSS99"
$PN"228"6;
"VSS98"
$PN"226"6;
"VSS97"
$PN"224"6;
"VSS96"
$PN"222"6;
"VSS95"
$PN"219"6;
"VSS94"
$PN"216"6;
"VSS93"
$PN"214"6;
"VSS92"
$PN"212"6;
"VSS91"
$PN"210"6;
"VSS90"
$PN"208"6;
"VSS89"
$PN"206"6;
"VSS88"
$PN"204"6;
"VSS87"
$PN"202"6;
"VSS86"
$PN"199"6;
"VSS85"
$PN"197"6;
"VSS84"
$PN"195"6;
"VSS83"
$PN"193"6;
"VSS82"
$PN"191"6;
"VSS81"
$PN"188"6;
"VSS80"
$PN"186"6;
"VSS79"
$PN"184"6;
"VSS78"
$PN"182"6;
"VSS77"
$PN"180"6;
"VSS76"
$PN"177"6;
"VSS75"
$PN"175"6;
"VSS74"
$PN"173"6;
"VSS73"
$PN"171"6;
"VSS72"
$PN"169"6;
"VSS71"
$PN"166"6;
"VSS70"
$PN"164"6;
"VSS69"
$PN"162"6;
"VSS68"
$PN"160"6;
"VSS67"
$PN"158"6;
"VSS66"
$PN"155"6;
"VSS65"
$PN"153"6;
"VSS64"
$PN"151"6;
"VSS63"
$PN"143"5;
"VSS59"
$PN"134"5;
"VSS57"
$PN"130"5;
"VSS56"
$PN"128"5;
"VSS55"
$PN"125"5;
"VSS54"
$PN"123"5;
"VSS53"
$PN"121"5;
"VSS52"
$PN"119"5;
"VSS51"
$PN"117"5;
"VSS50"
$PN"114"5;
"VSS49"
$PN"112"5;
"VSS48"
$PN"110"5;
"VSS47"
$PN"108"5;
"VSS46"
$PN"106"5;
"VSS45"
$PN"103"5;
"VSS44"
$PN"101"5;
"VSS43"
$PN"99"5;
"VSS42"
$PN"97"5;
"VSS41"
$PN"95"5;
"VSS40"
$PN"92"5;
"VSS39"
$PN"90"5;
"VSS38"
$PN"88"5;
"VSS37"
$PN"85"5;
"VSS36"
$PN"83"5;
"VSS35"
$PN"81"5;
"VSS34"
$PN"79"5;
"VSS33"
$PN"77"5;
"VSS32"
$PN"75"5;
"VSS31"
$PN"73"5;
"VSS30"
$PN"71"5;
"VSS29"
$PN"69"5;
"VSS28"
$PN"67"5;
"VSS27"
$PN"65"5;
"VSS26"
$PN"63"5;
"VSS25"
$PN"61"5;
"VSS24"
$PN"59"5;
"VSS23"
$PN"57"5;
"VSS22"
$PN"54"5;
"VSS21"
$PN"52"5;
"VSS20"
$PN"50"5;
"VSS19"
$PN"48"5;
"VSS18"
$PN"46"5;
"VSS17"
$PN"43"5;
"VSS16"
$PN"41"5;
"VSS15"
$PN"39"5;
"VSS14"
$PN"37"5;
"VSS13"
$PN"35"5;
"VSS12"
$PN"32"5;
"VSS11"
$PN"30"5;
"VSS10"
$PN"28"5;
"VSS9"
$PN"26"5;
"VSS8"
$PN"24"5;
"VSS7"
$PN"21"5;
"VSS6"
$PN"19"5;
"VSS5"
$PN"17"5;
"VSS4"
$PN"15"5;
"VSS3"
$PN"13"5;
"VSS2"
$PN"10"5;
"VSS1"
$PN"8"5;
"VSS0"
$PN"6"5;
%"UNIVERSAL_GND"
"1","(5775,475)","0","logical_power","I65";
;
CDS_LIB"logical_power"
HDL_POWER"GND";
"A"5;
%"TAP"
"1","(-350,975)","0","standard","I66";
;
CDS_LIB"standard"
BODY_TYPE"PLUMBING"
HDL_TAP"TRUE";
"B \NAC \NWC"10;
"S \NAC"
BN"0"172;
%"TAP"
"1","(-350,1025)","0","standard","I67";
;
CDS_LIB"standard"
BODY_TYPE"PLUMBING"
HDL_TAP"TRUE";
"B \NAC \NWC"10;
"S \NAC"
BN"1"171;
%"TAP"
"1","(-350,1075)","0","standard","I68";
;
CDS_LIB"standard"
BODY_TYPE"PLUMBING"
HDL_TAP"TRUE";
"B \NAC \NWC"10;
"S \NAC"
BN"2"170;
%"TAP"
"1","(-350,1125)","0","standard","I69";
;
CDS_LIB"standard"
BODY_TYPE"PLUMBING"
HDL_TAP"TRUE";
"B \NAC \NWC"10;
"S \NAC"
BN"3"169;
%"TAP"
"1","(-350,1225)","0","standard","I70";
;
CDS_LIB"standard"
BODY_TYPE"PLUMBING"
HDL_TAP"TRUE";
"B \NAC \NWC"10;
"S \NAC"
BN"5"167;
%"TAP"
"1","(-350,1175)","0","standard","I71";
;
CDS_LIB"standard"
BODY_TYPE"PLUMBING"
HDL_TAP"TRUE";
"B \NAC \NWC"10;
"S \NAC"
BN"4"168;
%"TAP"
"1","(-350,1325)","0","standard","I72";
;
CDS_LIB"standard"
BODY_TYPE"PLUMBING"
HDL_TAP"TRUE";
"B \NAC \NWC"10;
"S \NAC"
BN"7"165;
%"TAP"
"1","(-350,1275)","0","standard","I73";
;
CDS_LIB"standard"
BODY_TYPE"PLUMBING"
HDL_TAP"TRUE";
"B \NAC \NWC"10;
"S \NAC"
BN"6"166;
%"TAP"
"1","(-350,1425)","0","standard","I74";
;
CDS_LIB"standard"
BODY_TYPE"PLUMBING"
HDL_TAP"TRUE";
"B \NAC \NWC"10;
"S \NAC"
BN"9"163;
%"TAP"
"1","(-350,1375)","0","standard","I75";
;
CDS_LIB"standard"
BODY_TYPE"PLUMBING"
HDL_TAP"TRUE";
"B \NAC \NWC"10;
"S \NAC"
BN"8"164;
%"TAP"
"1","(-350,1475)","0","standard","I76";
;
CDS_LIB"standard"
BODY_TYPE"PLUMBING"
HDL_TAP"TRUE";
"B \NAC \NWC"10;
"S \NAC"
BN"10"162;
%"TAP"
"1","(-350,1575)","0","standard","I77";
;
CDS_LIB"standard"
BODY_TYPE"PLUMBING"
HDL_TAP"TRUE";
"B \NAC \NWC"10;
"S \NAC"
BN"12"160;
%"TAP"
"1","(-350,1525)","0","standard","I78";
;
CDS_LIB"standard"
BODY_TYPE"PLUMBING"
HDL_TAP"TRUE";
"B \NAC \NWC"10;
"S \NAC"
BN"11"161;
%"TAP"
"1","(-350,1675)","0","standard","I79";
;
CDS_LIB"standard"
BODY_TYPE"PLUMBING"
HDL_TAP"TRUE";
"B \NAC \NWC"10;
"S \NAC"
BN"14"158;
%"TAP"
"1","(-350,1625)","0","standard","I80";
;
CDS_LIB"standard"
BODY_TYPE"PLUMBING"
HDL_TAP"TRUE";
"B \NAC \NWC"10;
"S \NAC"
BN"13"159;
%"TAP"
"1","(-350,1725)","0","standard","I81";
;
CDS_LIB"standard"
BODY_TYPE"PLUMBING"
HDL_TAP"TRUE";
"B \NAC \NWC"10;
"S \NAC"
BN"15"157;
%"TAP"
"1","(-350,1825)","0","standard","I82";
;
CDS_LIB"standard"
BODY_TYPE"PLUMBING"
HDL_TAP"TRUE";
"B \NAC \NWC"10;
"S \NAC"
BN"17"155;
%"TAP"
"1","(-350,1775)","0","standard","I83";
;
CDS_LIB"standard"
BODY_TYPE"PLUMBING"
HDL_TAP"TRUE";
"B \NAC \NWC"10;
"S \NAC"
BN"16"156;
%"TAP"
"1","(-350,1875)","0","standard","I84";
;
CDS_LIB"standard"
BODY_TYPE"PLUMBING"
HDL_TAP"TRUE";
"B \NAC \NWC"10;
"S \NAC"
BN"18"154;
%"TAP"
"1","(-350,1925)","0","standard","I85";
;
CDS_LIB"standard"
BODY_TYPE"PLUMBING"
HDL_TAP"TRUE";
"B \NAC \NWC"10;
"S \NAC"
BN"19"153;
%"TAP"
"1","(-350,1975)","0","standard","I86";
;
CDS_LIB"standard"
BODY_TYPE"PLUMBING"
HDL_TAP"TRUE";
"B \NAC \NWC"10;
"S \NAC"
BN"20"152;
%"TAP"
"1","(-350,2075)","0","standard","I87";
;
CDS_LIB"standard"
BODY_TYPE"PLUMBING"
HDL_TAP"TRUE";
"B \NAC \NWC"10;
"S \NAC"
BN"22"150;
%"TAP"
"1","(-350,2025)","0","standard","I88";
;
CDS_LIB"standard"
BODY_TYPE"PLUMBING"
HDL_TAP"TRUE";
"B \NAC \NWC"10;
"S \NAC"
BN"21"151;
%"TAP"
"1","(-350,2125)","0","standard","I89";
;
CDS_LIB"standard"
BODY_TYPE"PLUMBING"
HDL_TAP"TRUE";
"B \NAC \NWC"10;
"S \NAC"
BN"23"149;
%"TAP"
"1","(-350,2175)","0","standard","I90";
;
CDS_LIB"standard"
BODY_TYPE"PLUMBING"
HDL_TAP"TRUE";
"B \NAC \NWC"10;
"S \NAC"
BN"24"148;
%"TAP"
"1","(-350,2225)","0","standard","I91";
;
CDS_LIB"standard"
BODY_TYPE"PLUMBING"
HDL_TAP"TRUE";
"B \NAC \NWC"10;
"S \NAC"
BN"25"147;
%"TAP"
"1","(-350,2275)","0","standard","I92";
;
CDS_LIB"standard"
BODY_TYPE"PLUMBING"
HDL_TAP"TRUE";
"B \NAC \NWC"10;
"S \NAC"
BN"26"146;
%"TAP"
"1","(-350,2375)","0","standard","I93";
;
CDS_LIB"standard"
BODY_TYPE"PLUMBING"
HDL_TAP"TRUE";
"B \NAC \NWC"10;
"S \NAC"
BN"28"144;
%"TAP"
"1","(-350,2325)","0","standard","I94";
;
CDS_LIB"standard"
BODY_TYPE"PLUMBING"
HDL_TAP"TRUE";
"B \NAC \NWC"10;
"S \NAC"
BN"27"145;
%"TAP"
"1","(-350,2425)","0","standard","I95";
;
CDS_LIB"standard"
BODY_TYPE"PLUMBING"
HDL_TAP"TRUE";
"B \NAC \NWC"10;
"S \NAC"
BN"29"143;
%"TAP"
"1","(-350,2475)","0","standard","I96";
;
CDS_LIB"standard"
BODY_TYPE"PLUMBING"
HDL_TAP"TRUE";
"B \NAC \NWC"10;
"S \NAC"
BN"30"142;
%"TAP"
"1","(-350,2625)","0","standard","I97";
;
CDS_LIB"standard"
BODY_TYPE"PLUMBING"
HDL_TAP"TRUE";
"B \NAC \NWC"11;
"S \NAC"
BN"0"140;
%"TAP"
"1","(-350,2525)","0","standard","I98";
;
CDS_LIB"standard"
BODY_TYPE"PLUMBING"
HDL_TAP"TRUE";
"B \NAC \NWC"10;
"S \NAC"
BN"31"141;
%"TAP"
"1","(-350,2725)","0","standard","I99";
;
CDS_LIB"standard"
BODY_TYPE"PLUMBING"
HDL_TAP"TRUE";
"B \NAC \NWC"11;
"S \NAC"
BN"2"97;
END.
